(kicad_pcb
	(version 20260206)
	(generator "pcbnew")
	(generator_version "10.0")
	(general
		(thickness 1.6)
		(legacy_teardrops no)
	)
	(paper "A4")
	(title_block
		(title "Bryce Canyon_IOM_IOC_16318-2_OCP.brd")
		(comment 1 "Bryce Canyon / footprints 1413-1419 of 1605")
	)
	(layers
		(0 "F.Cu" signal "TOP")
		(4 "In1.Cu" signal "L2GND")
		(6 "In2.Cu" signal "L3")
		(8 "In3.Cu" signal "L4VCC")
		(10 "In4.Cu" signal "L5VCC")
		(12 "In5.Cu" signal "L6")
		(14 "In6.Cu" signal "L7GND")
		(2 "B.Cu" signal "BOTTOM")
		(9 "F.Adhes" user "F.Adhesive")
		(11 "B.Adhes" user "B.Adhesive")
		(13 "F.Paste" user "Package Geometry/Pastemask Top")
		(15 "B.Paste" user "Package Geometry/Pastemask Bottom")
		(5 "F.SilkS" user "Ref Des/Silkscreen Top")
		(7 "B.SilkS" user "Ref Des/Silkscreen Bottom")
		(1 "F.Mask" user "Board Geometry/Soldermask Top")
		(3 "B.Mask" user "Board Geometry/Soldermask Bottom")
		(17 "Dwgs.User" user "User.Drawings")
		(19 "Cmts.User" user "User.Comments")
		(21 "Eco1.User" user "User.Eco1")
		(23 "Eco2.User" user "User.Eco2")
		(25 "Edge.Cuts" user "Board Geometry/Outline")
		(27 "Margin" user)
		(31 "F.CrtYd" user "Package Geometry/Place Bound Top")
		(29 "B.CrtYd" user "Package Geometry/Place Bound Bottom")
		(35 "F.Fab" user "Ref Des/Assembly Top")
		(33 "B.Fab" user "Ref Des/Assembly Bottom")
	)
	(footprint ""
		(layer "B.Cu")
		(at 207.3148 -78.8416 -90)
		(property "Reference" "R615"
			(at 0 0 90)
			(layer "B.SilkS")
			(hide yes)
			(effects
				(font
					(size 1.27 1.27)
				)
				(justify mirror)
			)
		)
		(property "Value" "0R2J-2-GP"
			(at -0.064008 -3.993896 270)
			(unlocked yes)
			(layer "B.Fab")
			(hide yes)
			(effects
				(font
					(size 1.016 1.016)
					(thickness 0.1524)
				)
				(justify mirror)
			)
		)
		(property "Device Type" "R402H16"
			(at -0.064008 -5.517896 270)
			(unlocked yes)
			(layer "B.Fab")
			(hide yes)
			(effects
				(font
					(size 1.016 1.016)
					(thickness 0.1524)
				)
				(justify mirror)
			)
		)
		(duplicate_pad_numbers_are_jumpers no)
		(fp_line
			(start -0.508 -0.9398)
			(end 0.508 -0.9398)
			(stroke
				(width 0.1524)
				(type default)
			)
			(layer "B.SilkS")
		)
		(fp_line
			(start 0.508 -0.9398)
			(end 0.508 0.9398)
			(stroke
				(width 0.1524)
				(type default)
			)
			(layer "B.SilkS")
		)
		(fp_rect
			(start 0.508 0.9398)
			(end -0.508 -0.9398)
			(stroke
				(width 0)
				(type default)
			)
			(fill no)
			(layer "B.CrtYd")
		)
		(fp_rect
			(start 0.508 0.9398)
			(end -0.508 -0.9398)
			(stroke
				(width 0)
				(type default)
			)
			(fill no)
			(layer "B.Fab")
		)
		(pad "1" smd custom
			(at 0 -0.4445 90)
			(size 0.1397 0.1397)
			(layers "B.Cu" "B.Mask" "B.Paste")
			(net "GND_SEN")
			(options
				(clearance outline)
				(anchor circle)
			)
			(primitives
				(gr_poly
					(pts
						(arc
							(start -0.1778 0.2794)
							(mid -0.249642 0.249642)
							(end -0.2794 0.1778)
						)
						(arc
							(start -0.2794 -0.1778)
							(mid -0.249642 -0.249642)
							(end -0.1778 -0.2794)
						)
						(arc
							(start 0.1778 -0.2794)
							(mid 0.249642 -0.249642)
							(end 0.2794 -0.1778)
						)
						(arc
							(start 0.2794 0.1778)
							(mid 0.249642 0.249642)
							(end 0.1778 0.2794)
						)
					)
					(width 0)
					(fill yes)
				)
			)
		)
		(pad "2" smd custom
			(at 0 0.4445 90)
			(size 0.1397 0.1397)
			(layers "B.Cu" "B.Mask" "B.Paste")
			(net "GND")
			(options
				(clearance outline)
				(anchor circle)
			)
			(primitives
				(gr_poly
					(pts
						(arc
							(start -0.1778 0.2794)
							(mid -0.249642 0.249642)
							(end -0.2794 0.1778)
						)
						(arc
							(start -0.2794 -0.1778)
							(mid -0.249642 -0.249642)
							(end -0.1778 -0.2794)
						)
						(arc
							(start 0.1778 -0.2794)
							(mid 0.249642 -0.249642)
							(end 0.2794 -0.1778)
						)
						(arc
							(start 0.2794 0.1778)
							(mid 0.249642 0.249642)
							(end 0.1778 0.2794)
						)
					)
					(width 0)
					(fill yes)
				)
			)
		)
	)
	(footprint ""
		(layer "B.Cu")
		(at 192.405 -61.6204 90)
		(property "Reference" "C408"
			(at 0 0 90)
			(layer "B.SilkS")
			(hide yes)
			(effects
				(font
					(size 1.27 1.27)
				)
				(justify mirror)
			)
		)
		(property "Value" "SCD1U6D3V1KX-GP"
			(at 2.8321 -1.7399 90)
			(unlocked yes)
			(layer "B.Fab")
			(hide yes)
			(effects
				(font
					(size 1.016 1.016)
					(thickness 0.1524)
				)
				(justify mirror)
			)
		)
		(property "Device Type" "C0201H13"
			(at 2.8321 -3.2639 90)
			(unlocked yes)
			(layer "B.Fab")
			(hide yes)
			(effects
				(font
					(size 1.016 1.016)
					(thickness 0.1524)
				)
				(justify mirror)
			)
		)
		(duplicate_pad_numbers_are_jumpers no)
		(fp_rect
			(start 0.2794 0.6477)
			(end -0.2794 -0.6477)
			(stroke
				(width 0)
				(type default)
			)
			(fill no)
			(layer "B.CrtYd")
		)
		(fp_rect
			(start 0.2794 0.6477)
			(end -0.2794 -0.6477)
			(stroke
				(width 0)
				(type default)
			)
			(fill no)
			(layer "B.Fab")
		)
		(pad "1" smd custom
			(at 0 -0.2794 270)
			(size 0.0762 0.0762)
			(layers "B.Cu" "B.Mask" "B.Paste")
			(net "P0V975")
			(options
				(clearance outline)
				(anchor circle)
			)
			(primitives
				(gr_poly
					(pts
						(arc
							(start 0.1524 0.127)
							(mid 0.137521 0.162921)
							(end 0.1016 0.1778)
						)
						(arc
							(start -0.1016 0.1778)
							(mid -0.137521 0.162921)
							(end -0.1524 0.127)
						)
						(arc
							(start -0.1524 -0.127)
							(mid -0.137521 -0.162921)
							(end -0.1016 -0.1778)
						)
						(arc
							(start 0.1016 -0.1778)
							(mid 0.137521 -0.162921)
							(end 0.1524 -0.127)
						)
					)
					(width 0)
					(fill yes)
				)
			)
		)
		(pad "2" smd custom
			(at 0 0.2794 270)
			(size 0.0762 0.0762)
			(layers "B.Cu" "B.Mask" "B.Paste")
			(net "GND")
			(options
				(clearance outline)
				(anchor circle)
			)
			(primitives
				(gr_poly
					(pts
						(arc
							(start 0.1524 0.127)
							(mid 0.137521 0.162921)
							(end 0.1016 0.1778)
						)
						(arc
							(start -0.1016 0.1778)
							(mid -0.137521 0.162921)
							(end -0.1524 0.127)
						)
						(arc
							(start -0.1524 -0.127)
							(mid -0.137521 -0.162921)
							(end -0.1016 -0.1778)
						)
						(arc
							(start 0.1016 -0.1778)
							(mid 0.137521 -0.162921)
							(end 0.1524 -0.127)
						)
					)
					(width 0)
					(fill yes)
				)
			)
		)
	)
	(footprint ""
		(layer "B.Cu")
		(at 46.5074 -128.2192)
		(property "Reference" "R183"
			(at 0 0 0)
			(layer "B.SilkS")
			(hide yes)
			(effects
				(font
					(size 1.27 1.27)
				)
				(justify mirror)
			)
		)
		(property "Value" "2K2R2F-GP"
			(at -0.064008 -3.993896 0)
			(unlocked yes)
			(layer "B.Fab")
			(hide yes)
			(effects
				(font
					(size 1.016 1.016)
					(thickness 0.1524)
				)
				(justify mirror)
			)
		)
		(property "Device Type" "R402H16"
			(at -0.064008 -5.517896 0)
			(unlocked yes)
			(layer "B.Fab")
			(hide yes)
			(effects
				(font
					(size 1.016 1.016)
					(thickness 0.1524)
				)
				(justify mirror)
			)
		)
		(duplicate_pad_numbers_are_jumpers no)
		(fp_line
			(start -0.508 -0.9398)
			(end 0.508 -0.9398)
			(stroke
				(width 0.1524)
				(type default)
			)
			(layer "B.SilkS")
		)
		(fp_line
			(start 0.508 -0.9398)
			(end 0.508 0.9398)
			(stroke
				(width 0.1524)
				(type default)
			)
			(layer "B.SilkS")
		)
		(fp_rect
			(start 0.508 0.9398)
			(end -0.508 -0.9398)
			(stroke
				(width 0)
				(type default)
			)
			(fill no)
			(layer "B.CrtYd")
		)
		(fp_rect
			(start 0.508 0.9398)
			(end -0.508 -0.9398)
			(stroke
				(width 0)
				(type default)
			)
			(fill no)
			(layer "B.Fab")
		)
		(pad "1" smd custom
			(at 0 -0.4445 180)
			(size 0.1397 0.1397)
			(layers "B.Cu" "B.Mask" "B.Paste")
			(net "I2C_IOM_SCL")
			(options
				(clearance outline)
				(anchor circle)
			)
			(primitives
				(gr_poly
					(pts
						(arc
							(start -0.1778 0.2794)
							(mid -0.249642 0.249642)
							(end -0.2794 0.1778)
						)
						(arc
							(start -0.2794 -0.1778)
							(mid -0.249642 -0.249642)
							(end -0.1778 -0.2794)
						)
						(arc
							(start 0.1778 -0.2794)
							(mid 0.249642 -0.249642)
							(end 0.2794 -0.1778)
						)
						(arc
							(start 0.2794 0.1778)
							(mid 0.249642 0.249642)
							(end 0.1778 0.2794)
						)
					)
					(width 0)
					(fill yes)
				)
			)
		)
		(pad "2" smd custom
			(at 0 0.4445 180)
			(size 0.1397 0.1397)
			(layers "B.Cu" "B.Mask" "B.Paste")
			(net "P3V3_STBY")
			(options
				(clearance outline)
				(anchor circle)
			)
			(primitives
				(gr_poly
					(pts
						(arc
							(start -0.1778 0.2794)
							(mid -0.249642 0.249642)
							(end -0.2794 0.1778)
						)
						(arc
							(start -0.2794 -0.1778)
							(mid -0.249642 -0.249642)
							(end -0.1778 -0.2794)
						)
						(arc
							(start 0.1778 -0.2794)
							(mid 0.249642 -0.249642)
							(end 0.2794 -0.1778)
						)
						(arc
							(start 0.2794 0.1778)
							(mid 0.249642 0.249642)
							(end 0.1778 0.2794)
						)
					)
					(width 0)
					(fill yes)
				)
			)
		)
	)
	(footprint ""
		(layer "B.Cu")
		(at 148.0312 -19.6596 -90)
		(property "Reference" "C523"
			(at 0 0 90)
			(layer "B.SilkS")
			(hide yes)
			(effects
				(font
					(size 1.27 1.27)
				)
				(justify mirror)
			)
		)
		(property "Value" "SCD1U16V2KX-3GP"
			(at -1.1811 -2.7051 270)
			(unlocked yes)
			(layer "B.Fab")
			(hide yes)
			(effects
				(font
					(size 1.016 1.016)
					(thickness 0.1524)
				)
				(justify mirror)
			)
		)
		(property "Device Type" "C402H22"
			(at -1.1811 -4.2291 270)
			(unlocked yes)
			(layer "B.Fab")
			(hide yes)
			(effects
				(font
					(size 1.016 1.016)
					(thickness 0.1524)
				)
				(justify mirror)
			)
		)
		(duplicate_pad_numbers_are_jumpers no)
		(fp_rect
			(start 0.4318 0.9525)
			(end -0.4318 -0.9525)
			(stroke
				(width 0)
				(type default)
			)
			(fill no)
			(layer "B.CrtYd")
		)
		(fp_rect
			(start 0.4318 0.9525)
			(end -0.4318 -0.9525)
			(stroke
				(width 0)
				(type default)
			)
			(fill no)
			(layer "B.Fab")
		)
		(pad "1" smd custom
			(at 0 -0.4445 90)
			(size 0.1524 0.1524)
			(layers "B.Cu" "B.Mask" "B.Paste")
			(net "P3V3_STBY")
			(options
				(clearance outline)
				(anchor circle)
			)
			(primitives
				(gr_poly
					(pts
						(arc
							(start 0.3048 0.2032)
							(mid 0.275042 0.275042)
							(end 0.2032 0.3048)
						)
						(arc
							(start -0.2032 0.3048)
							(mid -0.275042 0.275042)
							(end -0.3048 0.2032)
						)
						(arc
							(start -0.3048 -0.2032)
							(mid -0.275042 -0.275042)
							(end -0.2032 -0.3048)
						)
						(arc
							(start 0.2032 -0.3048)
							(mid 0.275042 -0.275042)
							(end 0.3048 -0.2032)
						)
					)
					(width 0)
					(fill yes)
				)
			)
		)
		(pad "2" smd custom
			(at 0 0.4445 90)
			(size 0.1524 0.1524)
			(layers "B.Cu" "B.Mask" "B.Paste")
			(net "GND")
			(options
				(clearance outline)
				(anchor circle)
			)
			(primitives
				(gr_poly
					(pts
						(arc
							(start 0.3048 0.2032)
							(mid 0.275042 0.275042)
							(end 0.2032 0.3048)
						)
						(arc
							(start -0.2032 0.3048)
							(mid -0.275042 0.275042)
							(end -0.3048 0.2032)
						)
						(arc
							(start -0.3048 -0.2032)
							(mid -0.275042 -0.275042)
							(end -0.2032 -0.3048)
						)
						(arc
							(start 0.2032 -0.3048)
							(mid 0.275042 -0.275042)
							(end 0.3048 -0.2032)
						)
					)
					(width 0)
					(fill yes)
				)
			)
		)
	)
	(footprint ""
		(layer "B.Cu")
		(at 44.137326 -147.30476 90)
		(property "Reference" "C53"
			(at 0 0 90)
			(layer "B.SilkS")
			(hide yes)
			(effects
				(font
					(size 1.27 1.27)
				)
				(justify mirror)
			)
		)
		(property "Value" "SCD01U25V2KX-3GP"
			(at -1.1811 -2.7051 90)
			(unlocked yes)
			(layer "B.Fab")
			(hide yes)
			(effects
				(font
					(size 1.016 1.016)
					(thickness 0.1524)
				)
				(justify mirror)
			)
		)
		(property "Device Type" "C402H22"
			(at -1.1811 -4.2291 90)
			(unlocked yes)
			(layer "B.Fab")
			(hide yes)
			(effects
				(font
					(size 1.016 1.016)
					(thickness 0.1524)
				)
				(justify mirror)
			)
		)
		(duplicate_pad_numbers_are_jumpers no)
		(fp_rect
			(start 0.4318 0.9525)
			(end -0.4318 -0.9525)
			(stroke
				(width 0)
				(type default)
			)
			(fill no)
			(layer "B.CrtYd")
		)
		(fp_rect
			(start 0.4318 0.9525)
			(end -0.4318 -0.9525)
			(stroke
				(width 0)
				(type default)
			)
			(fill no)
			(layer "B.Fab")
		)
		(pad "1" smd custom
			(at 0 -0.4445 270)
			(size 0.1524 0.1524)
			(layers "B.Cu" "B.Mask" "B.Paste")
			(net "DDR_VREF")
			(options
				(clearance outline)
				(anchor circle)
			)
			(primitives
				(gr_poly
					(pts
						(arc
							(start 0.3048 0.2032)
							(mid 0.275042 0.275042)
							(end 0.2032 0.3048)
						)
						(arc
							(start -0.2032 0.3048)
							(mid -0.275042 0.275042)
							(end -0.3048 0.2032)
						)
						(arc
							(start -0.3048 -0.2032)
							(mid -0.275042 -0.275042)
							(end -0.2032 -0.3048)
						)
						(arc
							(start 0.2032 -0.3048)
							(mid 0.275042 -0.275042)
							(end 0.3048 -0.2032)
						)
					)
					(width 0)
					(fill yes)
				)
			)
		)
		(pad "2" smd custom
			(at 0 0.4445 270)
			(size 0.1524 0.1524)
			(layers "B.Cu" "B.Mask" "B.Paste")
			(net "GND")
			(options
				(clearance outline)
				(anchor circle)
			)
			(primitives
				(gr_poly
					(pts
						(arc
							(start 0.3048 0.2032)
							(mid 0.275042 0.275042)
							(end 0.2032 0.3048)
						)
						(arc
							(start -0.2032 0.3048)
							(mid -0.275042 0.275042)
							(end -0.3048 0.2032)
						)
						(arc
							(start -0.3048 -0.2032)
							(mid -0.275042 -0.275042)
							(end -0.2032 -0.3048)
						)
						(arc
							(start 0.2032 -0.3048)
							(mid 0.275042 -0.275042)
							(end 0.3048 -0.2032)
						)
					)
					(width 0)
					(fill yes)
				)
			)
		)
	)
	(footprint ""
		(layer "B.Cu")
		(at 185.97118 -57.7596 90)
		(property "Reference" "C431"
			(at 0 0 90)
			(layer "B.SilkS")
			(hide yes)
			(effects
				(font
					(size 1.27 1.27)
				)
				(justify mirror)
			)
		)
		(property "Value" "SCD1U16V2KX-3GP"
			(at -1.1811 -2.7051 90)
			(unlocked yes)
			(layer "B.Fab")
			(hide yes)
			(effects
				(font
					(size 1.016 1.016)
					(thickness 0.1524)
				)
				(justify mirror)
			)
		)
		(property "Device Type" "C402H22"
			(at -1.1811 -4.2291 90)
			(unlocked yes)
			(layer "B.Fab")
			(hide yes)
			(effects
				(font
					(size 1.016 1.016)
					(thickness 0.1524)
				)
				(justify mirror)
			)
		)
		(duplicate_pad_numbers_are_jumpers no)
		(fp_rect
			(start 0.4318 0.9525)
			(end -0.4318 -0.9525)
			(stroke
				(width 0)
				(type default)
			)
			(fill no)
			(layer "B.CrtYd")
		)
		(fp_rect
			(start 0.4318 0.9525)
			(end -0.4318 -0.9525)
			(stroke
				(width 0)
				(type default)
			)
			(fill no)
			(layer "B.Fab")
		)
		(pad "1" smd custom
			(at 0 -0.4445 270)
			(size 0.1524 0.1524)
			(layers "B.Cu" "B.Mask" "B.Paste")
			(net "P1V8")
			(options
				(clearance outline)
				(anchor circle)
			)
			(primitives
				(gr_poly
					(pts
						(arc
							(start 0.3048 0.2032)
							(mid 0.275042 0.275042)
							(end 0.2032 0.3048)
						)
						(arc
							(start -0.2032 0.3048)
							(mid -0.275042 0.275042)
							(end -0.3048 0.2032)
						)
						(arc
							(start -0.3048 -0.2032)
							(mid -0.275042 -0.275042)
							(end -0.2032 -0.3048)
						)
						(arc
							(start 0.2032 -0.3048)
							(mid 0.275042 -0.275042)
							(end 0.3048 -0.2032)
						)
					)
					(width 0)
					(fill yes)
				)
			)
		)
		(pad "2" smd custom
			(at 0 0.4445 270)
			(size 0.1524 0.1524)
			(layers "B.Cu" "B.Mask" "B.Paste")
			(net "GND")
			(options
				(clearance outline)
				(anchor circle)
			)
			(primitives
				(gr_poly
					(pts
						(arc
							(start 0.3048 0.2032)
							(mid 0.275042 0.275042)
							(end 0.2032 0.3048)
						)
						(arc
							(start -0.2032 0.3048)
							(mid -0.275042 0.275042)
							(end -0.3048 0.2032)
						)
						(arc
							(start -0.3048 -0.2032)
							(mid -0.275042 -0.275042)
							(end -0.2032 -0.3048)
						)
						(arc
							(start 0.2032 -0.3048)
							(mid 0.275042 -0.275042)
							(end 0.3048 -0.2032)
						)
					)
					(width 0)
					(fill yes)
				)
			)
		)
	)
	(footprint ""
		(layer "B.Cu")
		(at 25.334976 -141.03096 -90)
		(property "Reference" "R223"
			(at 0 0 90)
			(layer "B.SilkS")
			(hide yes)
			(effects
				(font
					(size 1.27 1.27)
				)
				(justify mirror)
			)
		)
		(property "Value" "120R2F-GP"
			(at -0.064008 -3.993896 270)
			(unlocked yes)
			(layer "B.Fab")
			(hide yes)
			(effects
				(font
					(size 1.016 1.016)
					(thickness 0.1524)
				)
				(justify mirror)
			)
		)
		(property "Device Type" "R402H16"
			(at -0.064008 -5.517896 270)
			(unlocked yes)
			(layer "B.Fab")
			(hide yes)
			(effects
				(font
					(size 1.016 1.016)
					(thickness 0.1524)
				)
				(justify mirror)
			)
		)
		(duplicate_pad_numbers_are_jumpers no)
		(fp_line
			(start -0.508 -0.9398)
			(end 0.508 -0.9398)
			(stroke
				(width 0.1524)
				(type default)
			)
			(layer "B.SilkS")
		)
		(fp_line
			(start 0.508 -0.9398)
			(end 0.508 0.9398)
			(stroke
				(width 0.1524)
				(type default)
			)
			(layer "B.SilkS")
		)
		(fp_rect
			(start 0.508 0.9398)
			(end -0.508 -0.9398)
			(stroke
				(width 0)
				(type default)
			)
			(fill no)
			(layer "B.CrtYd")
		)
		(fp_rect
			(start 0.508 0.9398)
			(end -0.508 -0.9398)
			(stroke
				(width 0)
				(type default)
			)
			(fill no)
			(layer "B.Fab")
		)
		(pad "1" smd custom
			(at 0 -0.4445 90)
			(size 0.1397 0.1397)
			(layers "B.Cu" "B.Mask" "B.Paste")
			(net "MEMRASN")
			(options
				(clearance outline)
				(anchor circle)
			)
			(primitives
				(gr_poly
					(pts
						(arc
							(start -0.1778 0.2794)
							(mid -0.249642 0.249642)
							(end -0.2794 0.1778)
						)
						(arc
							(start -0.2794 -0.1778)
							(mid -0.249642 -0.249642)
							(end -0.1778 -0.2794)
						)
						(arc
							(start 0.1778 -0.2794)
							(mid 0.249642 -0.249642)
							(end 0.2794 -0.1778)
						)
						(arc
							(start 0.2794 0.1778)
							(mid 0.249642 0.249642)
							(end 0.1778 0.2794)
						)
					)
					(width 0)
					(fill yes)
				)
			)
		)
		(pad "2" smd custom
			(at 0 0.4445 90)
			(size 0.1397 0.1397)
			(layers "B.Cu" "B.Mask" "B.Paste")
			(net "P1V2_STBY")
			(options
				(clearance outline)
				(anchor circle)
			)
			(primitives
				(gr_poly
					(pts
						(arc
							(start -0.1778 0.2794)
							(mid -0.249642 0.249642)
							(end -0.2794 0.1778)
						)
						(arc
							(start -0.2794 -0.1778)
							(mid -0.249642 -0.249642)
							(end -0.1778 -0.2794)
						)
						(arc
							(start 0.1778 -0.2794)
							(mid 0.249642 -0.249642)
							(end 0.2794 -0.1778)
						)
						(arc
							(start 0.2794 0.1778)
							(mid 0.249642 0.249642)
							(end 0.1778 0.2794)
						)
					)
					(width 0)
					(fill yes)
				)
			)
		)
	)
)
